(kicad_pcb
	(version 20260206)
	(generator "pcbnew")
	(generator_version "10.0")
	(general
		(thickness 1.6)
		(legacy_teardrops no)
	)
	(paper "A4")
	(title_block
		(title "Bryce Canyon_R.DPB_16317-1_OCP.brd")
		(comment 1 "Bryce Canyon / footprints 1988-1996 of 2099")
	)
	(layers
		(0 "F.Cu" signal "TOP")
		(4 "In1.Cu" signal "L2GND")
		(6 "In2.Cu" signal "L3")
		(8 "In3.Cu" signal "L4VCC")
		(10 "In4.Cu" signal "L5VCC")
		(12 "In5.Cu" signal "L6")
		(14 "In6.Cu" signal "L7GND")
		(2 "B.Cu" signal "BOTTOM")
		(9 "F.Adhes" user "F.Adhesive")
		(11 "B.Adhes" user "B.Adhesive")
		(13 "F.Paste" user "Package Geometry/Pastemask Top")
		(15 "B.Paste" user "Package Geometry/Pastemask Bottom")
		(5 "F.SilkS" user "Ref Des/Silkscreen Top")
		(7 "B.SilkS" user "Ref Des/Silkscreen Bottom")
		(1 "F.Mask" user "Board Geometry/Soldermask Top")
		(3 "B.Mask" user "Board Geometry/Soldermask Bottom")
		(17 "Dwgs.User" user "User.Drawings")
		(19 "Cmts.User" user "User.Comments")
		(21 "Eco1.User" user "User.Eco1")
		(23 "Eco2.User" user "User.Eco2")
		(25 "Edge.Cuts" user "Board Geometry/Outline")
		(27 "Margin" user)
		(31 "F.CrtYd" user "Package Geometry/Place Bound Top")
		(29 "B.CrtYd" user "Package Geometry/Place Bound Bottom")
		(35 "F.Fab" user "Ref Des/Assembly Top")
		(33 "B.Fab" user "Ref Des/Assembly Bottom")
	)
	(footprint ""
		(layer "B.Cu")
		(at 33.57626 -112.239806 180)
		(property "Reference" "R1118"
			(at 0 0 0)
			(layer "B.SilkS")
			(hide yes)
			(effects
				(font
					(size 1.27 1.27)
				)
				(justify mirror)
			)
		)
		(property "Value" "2D2R3-1-U-GP"
			(at 0.0254 -2.5146 180)
			(unlocked yes)
			(layer "B.Fab")
			(hide yes)
			(effects
				(font
					(size 1.016 1.016)
					(thickness 0.1524)
				)
				(justify mirror)
			)
		)
		(property "Device Type" "R603H22"
			(at 0.0254 -4.0386 180)
			(unlocked yes)
			(layer "B.Fab")
			(hide yes)
			(effects
				(font
					(size 1.016 1.016)
					(thickness 0.1524)
				)
				(justify mirror)
			)
		)
		(duplicate_pad_numbers_are_jumpers no)
		(fp_line
			(start 0.4826 0)
			(end 0.2032 0)
			(stroke
				(width 0.2032)
				(type default)
			)
			(layer "B.SilkS")
		)
		(fp_line
			(start -0.2032 0)
			(end -0.4826 0)
			(stroke
				(width 0.2032)
				(type default)
			)
			(layer "B.SilkS")
		)
		(fp_rect
			(start 0.5842 1.3335)
			(end -0.5842 -1.3335)
			(stroke
				(width 0)
				(type default)
			)
			(fill no)
			(layer "B.CrtYd")
		)
		(fp_rect
			(start 0.5842 1.3335)
			(end -0.5842 -1.3335)
			(stroke
				(width 0)
				(type default)
			)
			(fill no)
			(layer "B.Fab")
		)
		(pad "1" smd custom
			(at 0 -0.762)
			(size 0.2159 0.2159)
			(layers "B.Cu" "B.Mask" "B.Paste")
			(net "P12V_B")
			(options
				(clearance outline)
				(anchor circle)
			)
			(primitives
				(gr_poly
					(pts
						(arc
							(start -0.3302 0.4318)
							(mid -0.402042 0.402042)
							(end -0.4318 0.3302)
						)
						(arc
							(start -0.4318 -0.3302)
							(mid -0.402042 -0.402042)
							(end -0.3302 -0.4318)
						)
						(arc
							(start 0.3302 -0.4318)
							(mid 0.402042 -0.402042)
							(end 0.4318 -0.3302)
						)
						(arc
							(start 0.4318 0.3302)
							(mid 0.402042 0.402042)
							(end 0.3302 0.4318)
						)
					)
					(width 0)
					(fill yes)
				)
			)
		)
		(pad "2" smd custom
			(at 0 0.762)
			(size 0.2159 0.2159)
			(layers "B.Cu" "B.Mask" "B.Paste")
			(net "P12V_B_2_VDD_U32")
			(options
				(clearance outline)
				(anchor circle)
			)
			(primitives
				(gr_poly
					(pts
						(arc
							(start -0.3302 0.4318)
							(mid -0.402042 0.402042)
							(end -0.4318 0.3302)
						)
						(arc
							(start -0.4318 -0.3302)
							(mid -0.402042 -0.402042)
							(end -0.3302 -0.4318)
						)
						(arc
							(start 0.3302 -0.4318)
							(mid 0.402042 -0.402042)
							(end 0.4318 -0.3302)
						)
						(arc
							(start 0.4318 0.3302)
							(mid 0.402042 0.402042)
							(end 0.3302 0.4318)
						)
					)
					(width 0)
					(fill yes)
				)
			)
		)
	)
	(footprint ""
		(layer "B.Cu")
		(at 57.141872 -117.908832 180)
		(property "Reference" "C646"
			(at 0 0 0)
			(layer "B.SilkS")
			(hide yes)
			(effects
				(font
					(size 1.27 1.27)
				)
				(justify mirror)
			)
		)
		(property "Value" "SCD1U50V3KX-GP"
			(at 0 -2.8194 180)
			(unlocked yes)
			(layer "B.Fab")
			(hide yes)
			(effects
				(font
					(size 1.016 1.016)
					(thickness 0.1524)
				)
				(justify mirror)
			)
		)
		(property "Device Type" "C603H36"
			(at 0 -4.3434 180)
			(unlocked yes)
			(layer "B.Fab")
			(hide yes)
			(effects
				(font
					(size 1.016 1.016)
					(thickness 0.1524)
				)
				(justify mirror)
			)
		)
		(duplicate_pad_numbers_are_jumpers no)
		(fp_line
			(start -0.508 0)
			(end 0.508 0)
			(stroke
				(width 0.2032)
				(type default)
			)
			(layer "B.SilkS")
		)
		(fp_rect
			(start 0.5842 1.3335)
			(end -0.5842 -1.3335)
			(stroke
				(width 0)
				(type default)
			)
			(fill no)
			(layer "B.CrtYd")
		)
		(fp_rect
			(start 0.5842 1.3335)
			(end -0.5842 -1.3335)
			(stroke
				(width 0)
				(type default)
			)
			(fill no)
			(layer "B.Fab")
		)
		(pad "1" smd custom
			(at 0 -0.762)
			(size 0.2159 0.2159)
			(layers "B.Cu" "B.Mask" "B.Paste")
			(net "P5V_B_2")
			(options
				(clearance outline)
				(anchor circle)
			)
			(primitives
				(gr_poly
					(pts
						(arc
							(start -0.3302 0.4318)
							(mid -0.402042 0.402042)
							(end -0.4318 0.3302)
						)
						(arc
							(start -0.4318 -0.3302)
							(mid -0.402042 -0.402042)
							(end -0.3302 -0.4318)
						)
						(arc
							(start 0.3302 -0.4318)
							(mid 0.402042 -0.402042)
							(end 0.4318 -0.3302)
						)
						(arc
							(start 0.4318 0.3302)
							(mid 0.402042 0.402042)
							(end 0.3302 0.4318)
						)
					)
					(width 0)
					(fill yes)
				)
			)
		)
		(pad "2" smd custom
			(at 0 0.762)
			(size 0.2159 0.2159)
			(layers "B.Cu" "B.Mask" "B.Paste")
			(net "P5V_B_2_LL_R")
			(options
				(clearance outline)
				(anchor circle)
			)
			(primitives
				(gr_poly
					(pts
						(arc
							(start -0.3302 0.4318)
							(mid -0.402042 0.402042)
							(end -0.4318 0.3302)
						)
						(arc
							(start -0.4318 -0.3302)
							(mid -0.402042 -0.402042)
							(end -0.3302 -0.4318)
						)
						(arc
							(start 0.3302 -0.4318)
							(mid 0.402042 -0.402042)
							(end 0.4318 -0.3302)
						)
						(arc
							(start 0.4318 0.3302)
							(mid 0.402042 0.402042)
							(end 0.3302 0.4318)
						)
					)
					(width 0)
					(fill yes)
				)
			)
		)
	)
	(footprint ""
		(layer "B.Cu")
		(at 37.23386 -111.833406 180)
		(property "Reference" "C636"
			(at 0 0 0)
			(layer "B.SilkS")
			(hide yes)
			(effects
				(font
					(size 1.27 1.27)
				)
				(justify mirror)
			)
		)
		(property "Value" "SC10U16V5KX-7-GP-U"
			(at 0.0762 -6.1214 180)
			(unlocked yes)
			(layer "B.Fab")
			(hide yes)
			(effects
				(font
					(size 1.016 1.016)
					(thickness 0.1524)
				)
				(justify mirror)
			)
		)
		(property "Device Type" "C805H58"
			(at 0.0762 -8.1534 180)
			(unlocked yes)
			(layer "B.Fab")
			(hide yes)
			(effects
				(font
					(size 1.016 1.016)
					(thickness 0.1524)
				)
				(justify mirror)
			)
		)
		(duplicate_pad_numbers_are_jumpers no)
		(fp_line
			(start -0.635 0)
			(end 0.635 0)
			(stroke
				(width 0.508)
				(type default)
			)
			(layer "B.SilkS")
		)
		(fp_rect
			(start 0.9652 1.778)
			(end -0.9652 -1.778)
			(stroke
				(width 0)
				(type default)
			)
			(fill no)
			(layer "B.CrtYd")
		)
		(fp_poly
			(pts
				(xy 0.9652 -1.778) (xy -0.9652 -1.778) (xy -0.9652 1.778) (xy 0.9652 1.778)
			)
			(stroke
				(width 0)
				(type default)
			)
			(fill no)
			(layer "B.Fab")
		)
		(pad "1" smd rect
			(at 0 -0.9652)
			(size 1.397 1.143)
			(layers "B.Cu" "B.Mask" "B.Paste")
			(net "P12V_B_2_VIN_U32")
		)
		(pad "2" smd rect
			(at 0 0.9652)
			(size 1.397 1.143)
			(layers "B.Cu" "B.Mask" "B.Paste")
			(net "GND")
		)
	)
	(footprint ""
		(layer "B.Cu")
		(at 24.450802 -230.63835 90)
		(property "Reference" "C630"
			(at 0 0 90)
			(layer "B.SilkS")
			(hide yes)
			(effects
				(font
					(size 1.27 1.27)
				)
				(justify mirror)
			)
		)
		(property "Value" "SC68P50V2JN-2-GP"
			(at -1.1811 -2.7051 90)
			(unlocked yes)
			(layer "B.Fab")
			(hide yes)
			(effects
				(font
					(size 1.016 1.016)
					(thickness 0.1524)
				)
				(justify mirror)
			)
		)
		(property "Device Type" "C402H22"
			(at -1.1811 -4.2291 90)
			(unlocked yes)
			(layer "B.Fab")
			(hide yes)
			(effects
				(font
					(size 1.016 1.016)
					(thickness 0.1524)
				)
				(justify mirror)
			)
		)
		(duplicate_pad_numbers_are_jumpers no)
		(fp_rect
			(start 0.4318 0.9525)
			(end -0.4318 -0.9525)
			(stroke
				(width 0)
				(type default)
			)
			(fill no)
			(layer "B.CrtYd")
		)
		(fp_rect
			(start 0.4318 0.9525)
			(end -0.4318 -0.9525)
			(stroke
				(width 0)
				(type default)
			)
			(fill no)
			(layer "B.Fab")
		)
		(pad "1" smd custom
			(at 0 -0.4445 270)
			(size 0.1524 0.1524)
			(layers "B.Cu" "B.Mask" "B.Paste")
			(net "P5V_B_1_VFB")
			(options
				(clearance outline)
				(anchor circle)
			)
			(primitives
				(gr_poly
					(pts
						(arc
							(start 0.3048 0.2032)
							(mid 0.275042 0.275042)
							(end 0.2032 0.3048)
						)
						(arc
							(start -0.2032 0.3048)
							(mid -0.275042 0.275042)
							(end -0.3048 0.2032)
						)
						(arc
							(start -0.3048 -0.2032)
							(mid -0.275042 -0.275042)
							(end -0.2032 -0.3048)
						)
						(arc
							(start 0.2032 -0.3048)
							(mid 0.275042 -0.275042)
							(end 0.3048 -0.2032)
						)
					)
					(width 0)
					(fill yes)
				)
			)
		)
		(pad "2" smd custom
			(at 0 0.4445 270)
			(size 0.1524 0.1524)
			(layers "B.Cu" "B.Mask" "B.Paste")
			(net "P5V_B_1_VFB_R")
			(options
				(clearance outline)
				(anchor circle)
			)
			(primitives
				(gr_poly
					(pts
						(arc
							(start 0.3048 0.2032)
							(mid 0.275042 0.275042)
							(end 0.2032 0.3048)
						)
						(arc
							(start -0.2032 0.3048)
							(mid -0.275042 0.275042)
							(end -0.3048 0.2032)
						)
						(arc
							(start -0.3048 -0.2032)
							(mid -0.275042 -0.275042)
							(end -0.2032 -0.3048)
						)
						(arc
							(start 0.2032 -0.3048)
							(mid 0.275042 -0.275042)
							(end 0.3048 -0.2032)
						)
					)
					(width 0)
					(fill yes)
				)
			)
		)
	)
	(footprint ""
		(layer "B.Cu")
		(at 73.55586 -117.167406 180)
		(property "Reference" "C651"
			(at 0 0 0)
			(layer "B.SilkS")
			(hide yes)
			(effects
				(font
					(size 1.27 1.27)
				)
				(justify mirror)
			)
		)
		(property "Value" "SC10U16V5KX-7-GP-U"
			(at 0.0762 -6.1214 180)
			(unlocked yes)
			(layer "B.Fab")
			(hide yes)
			(effects
				(font
					(size 1.016 1.016)
					(thickness 0.1524)
				)
				(justify mirror)
			)
		)
		(property "Device Type" "C805H58"
			(at 0.0762 -8.1534 180)
			(unlocked yes)
			(layer "B.Fab")
			(hide yes)
			(effects
				(font
					(size 1.016 1.016)
					(thickness 0.1524)
				)
				(justify mirror)
			)
		)
		(duplicate_pad_numbers_are_jumpers no)
		(fp_line
			(start -0.635 0)
			(end 0.635 0)
			(stroke
				(width 0.508)
				(type default)
			)
			(layer "B.SilkS")
		)
		(fp_rect
			(start 0.9652 1.778)
			(end -0.9652 -1.778)
			(stroke
				(width 0)
				(type default)
			)
			(fill no)
			(layer "B.CrtYd")
		)
		(fp_poly
			(pts
				(xy 0.9652 -1.778) (xy -0.9652 -1.778) (xy -0.9652 1.778) (xy 0.9652 1.778)
			)
			(stroke
				(width 0)
				(type default)
			)
			(fill no)
			(layer "B.Fab")
		)
		(pad "1" smd rect
			(at 0 -0.9652)
			(size 1.397 1.143)
			(layers "B.Cu" "B.Mask" "B.Paste")
			(net "P5V_B_2")
		)
		(pad "2" smd rect
			(at 0 0.9652)
			(size 1.397 1.143)
			(layers "B.Cu" "B.Mask" "B.Paste")
			(net "GND")
		)
	)
	(footprint ""
		(layer "B.Cu")
		(at 250.571 -284.607)
		(property "Reference" "R1179"
			(at 0 0 0)
			(layer "B.SilkS")
			(hide yes)
			(effects
				(font
					(size 1.27 1.27)
				)
				(justify mirror)
			)
		)
		(property "Value" "0R2J-2-GP"
			(at -0.064008 -3.993896 0)
			(unlocked yes)
			(layer "B.Fab")
			(hide yes)
			(effects
				(font
					(size 1.016 1.016)
					(thickness 0.1524)
				)
				(justify mirror)
			)
		)
		(property "Device Type" "R402H16"
			(at -0.064008 -5.517896 0)
			(unlocked yes)
			(layer "B.Fab")
			(hide yes)
			(effects
				(font
					(size 1.016 1.016)
					(thickness 0.1524)
				)
				(justify mirror)
			)
		)
		(duplicate_pad_numbers_are_jumpers no)
		(fp_line
			(start -0.508 -0.9398)
			(end 0.508 -0.9398)
			(stroke
				(width 0.1524)
				(type default)
			)
			(layer "B.SilkS")
		)
		(fp_line
			(start 0.508 -0.9398)
			(end 0.508 0.9398)
			(stroke
				(width 0.1524)
				(type default)
			)
			(layer "B.SilkS")
		)
		(fp_rect
			(start 0.508 0.9398)
			(end -0.508 -0.9398)
			(stroke
				(width 0)
				(type default)
			)
			(fill no)
			(layer "B.CrtYd")
		)
		(fp_rect
			(start 0.508 0.9398)
			(end -0.508 -0.9398)
			(stroke
				(width 0)
				(type default)
			)
			(fill no)
			(layer "B.Fab")
		)
		(pad "1" smd custom
			(at 0 -0.4445 180)
			(size 0.1397 0.1397)
			(layers "B.Cu" "B.Mask" "B.Paste")
			(net "P3V3_STBY_VBST_RR")
			(options
				(clearance outline)
				(anchor circle)
			)
			(primitives
				(gr_poly
					(pts
						(arc
							(start -0.1778 0.2794)
							(mid -0.249642 0.249642)
							(end -0.2794 0.1778)
						)
						(arc
							(start -0.2794 -0.1778)
							(mid -0.249642 -0.249642)
							(end -0.1778 -0.2794)
						)
						(arc
							(start 0.1778 -0.2794)
							(mid 0.249642 -0.249642)
							(end 0.2794 -0.1778)
						)
						(arc
							(start 0.2794 0.1778)
							(mid 0.249642 0.249642)
							(end 0.1778 0.2794)
						)
					)
					(width 0)
					(fill yes)
				)
			)
		)
		(pad "2" smd custom
			(at 0 0.4445 180)
			(size 0.1397 0.1397)
			(layers "B.Cu" "B.Mask" "B.Paste")
			(net "P3V3_STBY_VBST")
			(options
				(clearance outline)
				(anchor circle)
			)
			(primitives
				(gr_poly
					(pts
						(arc
							(start -0.1778 0.2794)
							(mid -0.249642 0.249642)
							(end -0.2794 0.1778)
						)
						(arc
							(start -0.2794 -0.1778)
							(mid -0.249642 -0.249642)
							(end -0.1778 -0.2794)
						)
						(arc
							(start 0.1778 -0.2794)
							(mid 0.249642 -0.249642)
							(end 0.2794 -0.1778)
						)
						(arc
							(start 0.2794 0.1778)
							(mid 0.249642 0.249642)
							(end 0.1778 0.2794)
						)
					)
					(width 0)
					(fill yes)
				)
			)
		)
	)
	(footprint ""
		(layer "B.Cu")
		(at 15.941802 -225.43135 90)
		(property "Reference" "C628"
			(at 0 0 90)
			(layer "B.SilkS")
			(hide yes)
			(effects
				(font
					(size 1.27 1.27)
				)
				(justify mirror)
			)
		)
		(property "Value" "SC1U16V3KX-5GP"
			(at 0 -2.8194 90)
			(unlocked yes)
			(layer "B.Fab")
			(hide yes)
			(effects
				(font
					(size 1.016 1.016)
					(thickness 0.1524)
				)
				(justify mirror)
			)
		)
		(property "Device Type" "C603H36"
			(at 0 -4.3434 90)
			(unlocked yes)
			(layer "B.Fab")
			(hide yes)
			(effects
				(font
					(size 1.016 1.016)
					(thickness 0.1524)
				)
				(justify mirror)
			)
		)
		(duplicate_pad_numbers_are_jumpers no)
		(fp_line
			(start -0.508 0)
			(end 0.508 0)
			(stroke
				(width 0.2032)
				(type default)
			)
			(layer "B.SilkS")
		)
		(fp_rect
			(start 0.5842 1.3335)
			(end -0.5842 -1.3335)
			(stroke
				(width 0)
				(type default)
			)
			(fill no)
			(layer "B.CrtYd")
		)
		(fp_rect
			(start 0.5842 1.3335)
			(end -0.5842 -1.3335)
			(stroke
				(width 0)
				(type default)
			)
			(fill no)
			(layer "B.Fab")
		)
		(pad "1" smd custom
			(at 0 -0.762 270)
			(size 0.2159 0.2159)
			(layers "B.Cu" "B.Mask" "B.Paste")
			(net "GND")
			(options
				(clearance outline)
				(anchor circle)
			)
			(primitives
				(gr_poly
					(pts
						(arc
							(start -0.3302 0.4318)
							(mid -0.402042 0.402042)
							(end -0.4318 0.3302)
						)
						(arc
							(start -0.4318 -0.3302)
							(mid -0.402042 -0.402042)
							(end -0.3302 -0.4318)
						)
						(arc
							(start 0.3302 -0.4318)
							(mid 0.402042 -0.402042)
							(end 0.4318 -0.3302)
						)
						(arc
							(start 0.4318 0.3302)
							(mid 0.402042 0.402042)
							(end 0.3302 0.4318)
						)
					)
					(width 0)
					(fill yes)
				)
			)
		)
		(pad "2" smd custom
			(at 0 0.762 270)
			(size 0.2159 0.2159)
			(layers "B.Cu" "B.Mask" "B.Paste")
			(net "P5V_B_1_VREG")
			(options
				(clearance outline)
				(anchor circle)
			)
			(primitives
				(gr_poly
					(pts
						(arc
							(start -0.3302 0.4318)
							(mid -0.402042 0.402042)
							(end -0.4318 0.3302)
						)
						(arc
							(start -0.4318 -0.3302)
							(mid -0.402042 -0.402042)
							(end -0.3302 -0.4318)
						)
						(arc
							(start 0.3302 -0.4318)
							(mid 0.402042 -0.402042)
							(end 0.4318 -0.3302)
						)
						(arc
							(start 0.4318 0.3302)
							(mid 0.402042 0.402042)
							(end 0.3302 0.4318)
						)
					)
					(width 0)
					(fill yes)
				)
			)
		)
	)
	(footprint ""
		(layer "B.Cu")
		(at 39.26586 -111.833406 180)
		(property "Reference" "C635"
			(at 0 0 0)
			(layer "B.SilkS")
			(hide yes)
			(effects
				(font
					(size 1.27 1.27)
				)
				(justify mirror)
			)
		)
		(property "Value" "SC10U16V5KX-7-GP-U"
			(at 0.0762 -6.1214 180)
			(unlocked yes)
			(layer "B.Fab")
			(hide yes)
			(effects
				(font
					(size 1.016 1.016)
					(thickness 0.1524)
				)
				(justify mirror)
			)
		)
		(property "Device Type" "C805H58"
			(at 0.0762 -8.1534 180)
			(unlocked yes)
			(layer "B.Fab")
			(hide yes)
			(effects
				(font
					(size 1.016 1.016)
					(thickness 0.1524)
				)
				(justify mirror)
			)
		)
		(duplicate_pad_numbers_are_jumpers no)
		(fp_line
			(start -0.635 0)
			(end 0.635 0)
			(stroke
				(width 0.508)
				(type default)
			)
			(layer "B.SilkS")
		)
		(fp_rect
			(start 0.9652 1.778)
			(end -0.9652 -1.778)
			(stroke
				(width 0)
				(type default)
			)
			(fill no)
			(layer "B.CrtYd")
		)
		(fp_poly
			(pts
				(xy 0.9652 -1.778) (xy -0.9652 -1.778) (xy -0.9652 1.778) (xy 0.9652 1.778)
			)
			(stroke
				(width 0)
				(type default)
			)
			(fill no)
			(layer "B.Fab")
		)
		(pad "1" smd rect
			(at 0 -0.9652)
			(size 1.397 1.143)
			(layers "B.Cu" "B.Mask" "B.Paste")
			(net "P12V_B_2_VIN_U32")
		)
		(pad "2" smd rect
			(at 0 0.9652)
			(size 1.397 1.143)
			(layers "B.Cu" "B.Mask" "B.Paste")
			(net "GND")
		)
	)
	(footprint ""
		(layer "B.Cu")
		(at 451.043802 -227.08235 -90)
		(property "Reference" "C660"
			(at 0 0 90)
			(layer "B.SilkS")
			(hide yes)
			(effects
				(font
					(size 1.27 1.27)
				)
				(justify mirror)
			)
		)
		(property "Value" "SC4D7U25V5KX-1-GP"
			(at 0.0762 -6.1214 270)
			(unlocked yes)
			(layer "B.Fab")
			(hide yes)
			(effects
				(font
					(size 1.016 1.016)
					(thickness 0.1524)
				)
				(justify mirror)
			)
		)
		(property "Device Type" "C805H58"
			(at 0.0762 -8.1534 270)
			(unlocked yes)
			(layer "B.Fab")
			(hide yes)
			(effects
				(font
					(size 1.016 1.016)
					(thickness 0.1524)
				)
				(justify mirror)
			)
		)
		(duplicate_pad_numbers_are_jumpers no)
		(fp_line
			(start -0.635 0)
			(end 0.635 0)
			(stroke
				(width 0.508)
				(type default)
			)
			(layer "B.SilkS")
		)
		(fp_rect
			(start 0.9652 1.778)
			(end -0.9652 -1.778)
			(stroke
				(width 0)
				(type default)
			)
			(fill no)
			(layer "B.CrtYd")
		)
		(fp_poly
			(pts
				(xy 0.9652 -1.778) (xy -0.9652 -1.778) (xy -0.9652 1.778) (xy 0.9652 1.778)
			)
			(stroke
				(width 0)
				(type default)
			)
			(fill no)
			(layer "B.Fab")
		)
		(pad "1" smd rect
			(at 0 -0.9652 90)
			(size 1.397 1.143)
			(layers "B.Cu" "B.Mask" "B.Paste")
			(net "P12V_B_3_VDD_U33")
		)
		(pad "2" smd rect
			(at 0 0.9652 90)
			(size 1.397 1.143)
			(layers "B.Cu" "B.Mask" "B.Paste")
			(net "GND")
		)
	)
)
